#ISCELL
  mstr_misc dns *
  *
#ISCELL
  pure_quanta quanta_title_block_c *
  *
#ISCELL
  pure_quanta_power universal_gnd *
  page478_i1
#CELL
  pure_quanta q_cap *
  page478_i10
#CELL
  pure_quanta q_cap *
  page478_i100
#ISCELL
  pure_quanta_power universal_gnd *
  page478_i101
#CELL
  pure_quanta q_capp *
  page478_i102
#ISCELL
  pure_quanta_power vcc15 *
  page478_i103
#CELL
  pure_quanta q_inductor *
  page478_i104
#ISCELL
  pure_quanta_power universal_power *
  page478_i105
#CELL
  pure_quanta q_res *
  page478_i106
#ISCELL
  pure_quanta_power universal_gnd *
  page478_i107
#CELL
  pure_quanta q_cap *
  page478_i108
#CELL
  pure_quanta q_cap *
  page478_i109
#CELL
  pure_quanta q_res *
  page478_i11
#CELL
  pure_quanta q_res *
  page478_i110
#ISCELL
  pure_quanta_power universal_gnd *
  page478_i111
#ISCELL
  pure_quanta_power universal_power *
  page478_i112
#ISCELL
  pure_quanta_power universal_gnd *
  page478_i113
#CELL
  pure_quanta q_cap *
  page478_i114
#CELL
  pure_quanta isl99390frztr5935 *
  page478_i12
#ISCELL
  pure_quanta_power universal_gnd *
  page478_i13
#CELL
  pure_quanta q_cap *
  page478_i14
#ISCELL
  pure_quanta_power universal_gnd *
  page478_i15
#CELL
  pure_quanta q_res *
  page478_i16
#ISCELL
  pure_quanta_power universal_gnd *
  page478_i17
#CELL
  pure_quanta q_cap *
  page478_i18
#CELL
  pure_quanta q_res *
  page478_i19
#CELL
  pure_quanta q_cap *
  page478_i2
#ISCELL
  pure_quanta_power universal_gnd *
  page478_i20
#CELL
  pure_quanta q_cap *
  page478_i21
#CELL
  pure_quanta q_inductor *
  page478_i22
#CELL
  pure_quanta q_cap *
  page478_i23
#ISCELL
  pure_quanta_power universal_gnd *
  page478_i24
#CELL
  pure_quanta q_cap *
  page478_i25
#CELL
  pure_quanta q_cap *
  page478_i26
#ISCELL
  pure_quanta_power universal_gnd *
  page478_i27
#CELL
  pure_quanta q_cap *
  page478_i28
#CELL
  pure_quanta q_cap *
  page478_i29
#ISCELL
  standard offpage *
  page478_i3
#CELL
  pure_quanta q_cap *
  page478_i30
#CELL
  pure_quanta q_capp *
  page478_i31
#CELL
  pure_quanta q_capp *
  page478_i32
#ISCELL
  pure_quanta_power universal_gnd *
  page478_i33
#ISCELL
  pure_quanta_power universal_gnd *
  page478_i34
#CELL
  pure_quanta q_cap *
  page478_i35
#CELL
  pure_quanta q_cap *
  page478_i36
#ISCELL
  pure_quanta_power universal_gnd *
  page478_i37
#CELL
  pure_quanta q_cap *
  page478_i38
#CELL
  pure_quanta q_cap *
  page478_i39
#ISCELL
  pure_quanta_power universal_gnd *
  page478_i4
#ISCELL
  pure_quanta_power universal_gnd *
  page478_i40
#ISCELL
  standard offpage *
  page478_i41
#CELL
  pure_quanta q_res *
  page478_i42
#ISCELL
  pure_quanta_power universal_power *
  page478_i43
#ISCELL
  pure_quanta_power universal_power *
  page478_i44
#ISCELL
  pure_quanta_power universal_gnd *
  page478_i45
#CELL
  pure_quanta q_res *
  page478_i46
#ISCELL
  standard offpage *
  page478_i47
#ISCELL
  pure_quanta_power universal_gnd *
  page478_i48
#ISCELL
  standard offpage *
  page478_i49
#CELL
  pure_quanta q_res *
  page478_i5
#ISCELL
  standard offpage *
  page478_i50
#CELL
  pure_quanta isl99390frztr5935 *
  page478_i51
#CELL
  pure_quanta q_cap *
  page478_i52
#CELL
  pure_quanta q_res *
  page478_i53
#ISCELL
  pure_quanta_power universal_gnd *
  page478_i54
#CELL
  pure_quanta q_cap *
  page478_i55
#CELL
  pure_quanta q_res *
  page478_i56
#ISCELL
  pure_quanta_power universal_power *
  page478_i57
#ISCELL
  pure_quanta_power universal_gnd *
  page478_i58
#CELL
  pure_quanta q_res *
  page478_i59
#ISCELL
  standard offpage *
  page478_i6
#ISCELL
  pure_quanta_power universal_gnd *
  page478_i60
#CELL
  pure_quanta q_cap *
  page478_i61
#CELL
  pure_quanta q_res *
  page478_i62
#ISCELL
  pure_quanta_power universal_gnd *
  page478_i63
#CELL
  pure_quanta q_cap *
  page478_i64
#CELL
  pure_quanta q_inductor *
  page478_i65
#CELL
  pure_quanta q_cap *
  page478_i66
#CELL
  pure_quanta q_cap *
  page478_i67
#CELL
  pure_quanta q_cap *
  page478_i68
#CELL
  pure_quanta q_capp *
  page478_i69
#ISCELL
  standard offpage *
  page478_i7
#CELL
  pure_quanta q_capp *
  page478_i70
#ISCELL
  pure_quanta_power universal_gnd *
  page478_i71
#CELL
  pure_quanta q_cap *
  page478_i72
#ISCELL
  pure_quanta_power universal_gnd *
  page478_i73
#CELL
  pure_quanta q_cap *
  page478_i74
#ISCELL
  pure_quanta_power universal_gnd *
  page478_i75
#CELL
  pure_quanta q_cap *
  page478_i76
#CELL
  pure_quanta q_cap *
  page478_i77
#ISCELL
  pure_quanta_power universal_gnd *
  page478_i78
#CELL
  pure_quanta q_cap *
  page478_i79
#ISCELL
  standard offpage *
  page478_i8
#CELL
  pure_quanta q_cap *
  page478_i80
#ISCELL
  pure_quanta_power universal_gnd *
  page478_i81
#CELL
  pure_quanta q_capp *
  page478_i82
#CELL
  pure_quanta q_capp *
  page478_i83
#CELL
  pure_quanta q_capp *
  page478_i84
#ISCELL
  pure_quanta_power universal_gnd *
  page478_i85
#CELL
  pure_quanta q_cap *
  page478_i86
#ISCELL
  pure_quanta_power universal_gnd *
  page478_i87
#CELL
  pure_quanta q_capp *
  page478_i88
#ISCELL
  pure_quanta_power vcc15 *
  page478_i89
#ISCELL
  pure_quanta_power universal_gnd *
  page478_i9
#ISCELL
  pure_quanta_power universal_gnd *
  page478_i90
#ISCELL
  pure_quanta_power vcc15 *
  page478_i92
#CELL
  pure_quanta q_capp *
  page478_i93
#CELL
  pure_quanta q_capp *
  page478_i94
#CELL
  pure_quanta q_capp *
  page478_i95
#ISCELL
  pure_quanta_power universal_gnd *
  page478_i96
#CELL
  pure_quanta q_res *
  page478_i97
#ISCELL
  pure_quanta_power vcc15 *
  page478_i98
#ISCELL
  pure_quanta_power universal_gnd *
  page478_i99
